# T6G (Grand Teton) — schematic netlist excerpt (pin names and nets, part order shuffled) for the footprints in the layout excerpt that follows; sources: Cadence DE-HDL packaged netlist, KiCad conversion of 04192023_DAF0TMB3IC0_F0TG_MB_C_brd_V02_OCP.brd

R376  Q_RES  15 1% CHIP  pkg 0402LF  page 11 : A = M_B_CPU0_ALERT_N ; B = M_B_CPU0_ALERT_R_N
C596  Q_CAP  4.7UF 6.3V 20% X6S  pkg 0402  page 290 : A = P1V8_CPU0_RT_1D ; B = GND

(kicad_pcb
	(version 20260206)
	(generator "pcbnew")
	(generator_version "10.0")
	(general
		(thickness 1.6)
		(legacy_teardrops no)
	)
	(paper "A4")
	(title_block
		(title "04192023_DAF0TMB3IC0_F0TG_MB_C_brd_V02_OCP.brd")
		(comment 1 "Grand Teton / footprints 6768-6769 of 8354")
	)
	(layers
		(0 "F.Cu" signal "TOP")
		(4 "In1.Cu" signal "GND")
		(6 "In2.Cu" signal "IN1")
		(8 "In3.Cu" signal "GND1")
		(10 "In4.Cu" signal "IN2")
		(12 "In5.Cu" signal "GND2")
		(14 "In6.Cu" signal "IN3")
		(16 "In7.Cu" signal "GND3")
		(18 "In8.Cu" signal "VCC")
		(20 "In9.Cu" signal "VCC1")
		(22 "In10.Cu" signal "GND4")
		(24 "In11.Cu" signal "IN4")
		(26 "In12.Cu" signal "GND5")
		(28 "In13.Cu" signal "IN5")
		(30 "In14.Cu" signal "GND6")
		(32 "In15.Cu" signal "IN6")
		(34 "In16.Cu" signal "GND7")
		(2 "B.Cu" signal "BOTTOM")
		(9 "F.Adhes" user "F.Adhesive")
		(11 "B.Adhes" user "B.Adhesive")
		(13 "F.Paste" user "Package Geometry/Pastemask Top")
		(15 "B.Paste" user "Package Geometry/Pastemask Bottom")
		(5 "F.SilkS" user "Ref Des/Silkscreen Top")
		(7 "B.SilkS" user "Ref Des/Silkscreen Bottom")
		(1 "F.Mask" user "Board Geometry/Soldermask Top")
		(3 "B.Mask" user "Board Geometry/Soldermask Bottom")
		(17 "Dwgs.User" user "User.Drawings")
		(19 "Cmts.User" user "User.Comments")
		(21 "Eco1.User" user "User.Eco1")
		(23 "Eco2.User" user "User.Eco2")
		(25 "Edge.Cuts" user "Board Geometry/Outline")
		(27 "Margin" user)
		(31 "F.CrtYd" user "Package Geometry/Place Bound Top")
		(29 "B.CrtYd" user "Package Geometry/Place Bound Bottom")
		(35 "F.Fab" user "Ref Des/Assembly Top")
		(33 "B.Fab" user "Ref Des/Assembly Bottom")
	)
	(footprint ""
		(layer "B.Cu")
		(at 300.82109 -244.08511 180)
		(property "Reference" "R376"
			(at 0 0 0)
			(layer "B.SilkS")
			(hide yes)
			(effects
				(font
					(size 1.27 1.27)
				)
				(justify mirror)
			)
		)
		(property "Value" ""
			(at 0 0 0)
			(layer "B.Fab")
			(effects
				(font
					(size 1.27 1.27)
				)
				(justify mirror)
			)
		)
		(duplicate_pad_numbers_are_jumpers no)
		(fp_line
			(start 0.7874 0.4064)
			(end 0.7874 -0.4064)
			(stroke
				(width 0.1524)
				(type default)
			)
			(layer "B.SilkS")
		)
		(fp_line
			(start 0.7874 -0.4064)
			(end -0.7874 -0.4064)
			(stroke
				(width 0.1524)
				(type default)
			)
			(layer "B.SilkS")
		)
		(fp_line
			(start -0.7874 0.4064)
			(end 0.7874 0.4064)
			(stroke
				(width 0.1524)
				(type default)
			)
			(layer "B.SilkS")
		)
		(fp_line
			(start -0.7874 -0.4064)
			(end -0.7874 0.4064)
			(stroke
				(width 0.1524)
				(type default)
			)
			(layer "B.SilkS")
		)
		(fp_line
			(start 0.67945 0.3048)
			(end 0.67945 -0.305054)
			(stroke
				(width 0.1)
				(type default)
			)
			(layer "B.Fab")
		)
		(fp_line
			(start 0.67945 -0.305054)
			(end 0.12065 -0.305054)
			(stroke
				(width 0.1)
				(type default)
			)
			(layer "B.Fab")
		)
		(fp_line
			(start 0.12065 0.3048)
			(end 0.67945 0.3048)
			(stroke
				(width 0.1)
				(type default)
			)
			(layer "B.Fab")
		)
		(fp_line
			(start 0.12065 0.2794)
			(end 0.12065 0.3048)
			(stroke
				(width 0.1)
				(type default)
			)
			(layer "B.Fab")
		)
		(fp_line
			(start 0.12065 -0.2794)
			(end -0.12065 -0.2794)
			(stroke
				(width 0.1)
				(type default)
			)
			(layer "B.Fab")
		)
		(fp_line
			(start 0.12065 -0.305054)
			(end 0.12065 -0.2794)
			(stroke
				(width 0.1)
				(type default)
			)
			(layer "B.Fab")
		)
		(fp_line
			(start -0.120396 0.3048)
			(end -0.120396 0.2794)
			(stroke
				(width 0.1)
				(type default)
			)
			(layer "B.Fab")
		)
		(fp_line
			(start -0.120396 0.2794)
			(end 0.12065 0.2794)
			(stroke
				(width 0.1)
				(type default)
			)
			(layer "B.Fab")
		)
		(fp_line
			(start -0.12065 -0.2794)
			(end -0.12065 -0.3048)
			(stroke
				(width 0.1)
				(type default)
			)
			(layer "B.Fab")
		)
		(fp_line
			(start -0.12065 -0.3048)
			(end -0.67945 -0.3048)
			(stroke
				(width 0.1)
				(type default)
			)
			(layer "B.Fab")
		)
		(fp_line
			(start -0.67945 0.3048)
			(end -0.120396 0.3048)
			(stroke
				(width 0.1)
				(type default)
			)
			(layer "B.Fab")
		)
		(fp_line
			(start -0.67945 -0.3048)
			(end -0.67945 0.3048)
			(stroke
				(width 0.1)
				(type default)
			)
			(layer "B.Fab")
		)
		(pad "1" smd circle
			(at 0.40005 0)
			(size 0 0)
			(layers "B.Cu" "B.Mask" "B.Paste")
			(net "M_B_CPU0_ALERT_N")
		)
		(pad "2" smd circle
			(at -0.40005 0)
			(size 0 0)
			(layers "B.Cu" "B.Mask" "B.Paste")
			(net "M_B_CPU0_ALERT_R_N")
		)
	)
	(footprint ""
		(layer "B.Cu")
		(at 361.595924 -395.127988 -90)
		(property "Reference" "C596"
			(at 0 0 90)
			(layer "B.SilkS")
			(hide yes)
			(effects
				(font
					(size 1.27 1.27)
				)
				(justify mirror)
			)
		)
		(property "Value" ""
			(at 0 0 90)
			(layer "B.Fab")
			(effects
				(font
					(size 1.27 1.27)
				)
				(justify mirror)
			)
		)
		(duplicate_pad_numbers_are_jumpers no)
		(fp_line
			(start -0.7874 0.4064)
			(end 0.7874 0.4064)
			(stroke
				(width 0.1524)
				(type default)
			)
			(layer "B.SilkS")
		)
		(fp_line
			(start 0.7874 0.4064)
			(end 0.7874 -0.4064)
			(stroke
				(width 0.1524)
				(type default)
			)
			(layer "B.SilkS")
		)
		(fp_line
			(start -0.7874 -0.4064)
			(end -0.7874 0.4064)
			(stroke
				(width 0.1524)
				(type default)
			)
			(layer "B.SilkS")
		)
		(fp_line
			(start 0.7874 -0.4064)
			(end -0.7874 -0.4064)
			(stroke
				(width 0.1524)
				(type default)
			)
			(layer "B.SilkS")
		)
		(fp_line
			(start -0.67945 0.3048)
			(end -0.120396 0.3048)
			(stroke
				(width 0.1)
				(type default)
			)
			(layer "B.Fab")
		)
		(fp_line
			(start -0.120396 0.3048)
			(end -0.120396 0.2794)
			(stroke
				(width 0.1)
				(type default)
			)
			(layer "B.Fab")
		)
		(fp_line
			(start 0.12065 0.3048)
			(end 0.67945 0.3048)
			(stroke
				(width 0.1)
				(type default)
			)
			(layer "B.Fab")
		)
		(fp_line
			(start 0.67945 0.3048)
			(end 0.67945 -0.305054)
			(stroke
				(width 0.1)
				(type default)
			)
			(layer "B.Fab")
		)
		(fp_line
			(start -0.120396 0.2794)
			(end 0.12065 0.2794)
			(stroke
				(width 0.1)
				(type default)
			)
			(layer "B.Fab")
		)
		(fp_line
			(start 0.12065 0.2794)
			(end 0.12065 0.3048)
			(stroke
				(width 0.1)
				(type default)
			)
			(layer "B.Fab")
		)
		(fp_line
			(start -0.12065 -0.2794)
			(end -0.12065 -0.3048)
			(stroke
				(width 0.1)
				(type default)
			)
			(layer "B.Fab")
		)
		(fp_line
			(start 0.12065 -0.2794)
			(end -0.12065 -0.2794)
			(stroke
				(width 0.1)
				(type default)
			)
			(layer "B.Fab")
		)
		(fp_line
			(start -0.67945 -0.3048)
			(end -0.67945 0.3048)
			(stroke
				(width 0.1)
				(type default)
			)
			(layer "B.Fab")
		)
		(fp_line
			(start -0.12065 -0.3048)
			(end -0.67945 -0.3048)
			(stroke
				(width 0.1)
				(type default)
			)
			(layer "B.Fab")
		)
		(fp_line
			(start 0.12065 -0.305054)
			(end 0.12065 -0.2794)
			(stroke
				(width 0.1)
				(type default)
			)
			(layer "B.Fab")
		)
		(fp_line
			(start 0.67945 -0.305054)
			(end 0.12065 -0.305054)
			(stroke
				(width 0.1)
				(type default)
			)
			(layer "B.Fab")
		)
		(pad "1" smd circle
			(at 0.40005 0 90)
			(size 0 0)
			(layers "B.Cu" "B.Mask" "B.Paste")
			(net "P1V8_CPU0_RT_1D")
		)
		(pad "2" smd circle
			(at -0.40005 0 90)
			(size 0 0)
			(layers "B.Cu" "B.Mask" "B.Paste")
			(net "GND")
		)
	)
)
